# BASEBOARD_FAB2 (Tioga Pass) — schematic netlist excerpt (pin names and nets, part order shuffled) for the footprints in the layout excerpt that follows; sources: Cadence DE-HDL packaged netlist, KiCad conversion of Wiwynn_Tioga_Pass_MB.brd

C7B2  CAP_A  0.1UF 16V 10% X7R  pkg 0402V  page 218 : A = VR_PVDDQ_DEF_VD12 ; B = GND
RT31  RES  0 5.0% CHIP  pkg 0603  page 219 : A = VR_PVDDQ_DEF_PH2_BOOT ; B = VR_PVDDQ_DEF_PH2_BOOT_R
R1C10  RES  0.0 5% EMPTY  pkg 0402  page 182 : A = SMB_LAN_STBY_LVC3_SDA ; B = FAN_TACH3_R

(kicad_pcb
	(version 20260206)
	(generator "pcbnew")
	(generator_version "10.0")
	(general
		(thickness 1.6)
		(legacy_teardrops no)
	)
	(paper "A4")
	(title_block
		(title "Wiwynn_Tioga_Pass_MB.brd")
		(comment 1 "Tioga Pass / footprints 1750-1752 of 4770")
	)
	(layers
		(0 "F.Cu" signal "TOP")
		(4 "In1.Cu" signal "L2GND")
		(6 "In2.Cu" signal "L3")
		(8 "In3.Cu" signal "L4GND")
		(10 "In4.Cu" signal "L5")
		(12 "In5.Cu" signal "L6GND")
		(14 "In6.Cu" signal "L7VCC")
		(16 "In7.Cu" signal "L8VCC")
		(18 "In8.Cu" signal "L9GND")
		(20 "In9.Cu" signal "L10")
		(22 "In10.Cu" signal "L11GND")
		(24 "In11.Cu" signal "L12")
		(26 "In12.Cu" signal "L13GND")
		(2 "B.Cu" signal "BOTTOM")
		(9 "F.Adhes" user "F.Adhesive")
		(11 "B.Adhes" user "B.Adhesive")
		(13 "F.Paste" user "Package Geometry/Pastemask Top")
		(15 "B.Paste" user "Package Geometry/Pastemask Bottom")
		(5 "F.SilkS" user "Ref Des/Silkscreen Top")
		(7 "B.SilkS" user "Ref Des/Silkscreen Bottom")
		(1 "F.Mask" user "Board Geometry/Soldermask Top")
		(3 "B.Mask" user "Board Geometry/Soldermask Bottom")
		(17 "Dwgs.User" user "User.Drawings")
		(19 "Cmts.User" user "User.Comments")
		(21 "Eco1.User" user "User.Eco1")
		(23 "Eco2.User" user "User.Eco2")
		(25 "Edge.Cuts" user "Board Geometry/Outline")
		(27 "Margin" user)
		(31 "F.CrtYd" user "Package Geometry/Place Bound Top")
		(29 "B.CrtYd" user "Package Geometry/Place Bound Bottom")
		(35 "F.Fab" user "Ref Des/Assembly Top")
		(33 "B.Fab" user "Ref Des/Assembly Bottom")
	)
	(footprint ""
		(layer "F.Cu")
		(at 14.224 -101.981)
		(property "Reference" "R1C10"
			(at 0 0 0)
			(layer "F.SilkS")
			(hide yes)
			(effects
				(font
					(size 1.27 1.27)
				)
			)
		)
		(property "Value" ""
			(at 0 0 0)
			(layer "F.Fab")
			(effects
				(font
					(size 1.27 1.27)
				)
			)
		)
		(duplicate_pad_numbers_are_jumpers no)
		(fp_poly
			(pts
				(xy -0.2794 -0.1016) (xy 0.2794 -0.1016) (xy 0.2794 0.9906) (xy -0.2794 0.9906)
			)
			(stroke
				(width 0)
				(type default)
			)
			(fill no)
			(layer "F.CrtYd")
		)
		(fp_line
			(start -0.2794 -0.1016)
			(end -0.2794 0.9906)
			(stroke
				(width 0.1)
				(type default)
			)
			(layer "F.Fab")
		)
		(fp_line
			(start -0.2794 0.9906)
			(end 0.2794 0.9906)
			(stroke
				(width 0.1)
				(type default)
			)
			(layer "F.Fab")
		)
		(fp_line
			(start 0.2794 -0.1016)
			(end -0.2794 -0.1016)
			(stroke
				(width 0.1)
				(type default)
			)
			(layer "F.Fab")
		)
		(fp_line
			(start 0.2794 0.9906)
			(end 0.2794 -0.1016)
			(stroke
				(width 0.1)
				(type default)
			)
			(layer "F.Fab")
		)
		(pad "1" smd rect
			(at 0 0)
			(size 0.508 0.508)
			(layers "F.Cu" "F.Mask" "F.Paste")
			(net "SMB_LAN_STBY_LVC3_SDA")
		)
		(pad "2" smd rect
			(at 0 0.889)
			(size 0.508 0.508)
			(layers "F.Cu" "F.Mask" "F.Paste")
			(net "FAN_TACH3_R")
		)
		(zone
			(layer "F.Cu")
			(hatch none 0.5)
			(connect_pads
				(clearance 0)
			)
			(min_thickness 0.25)
			(keepout
				(tracks allowed)
				(vias not_allowed)
				(pads allowed)
				(copperpour not_allowed)
				(footprints allowed)
			)
			(placement
				(enabled no)
				(sheetname "")
			)
			(fill
				(thermal_gap 0.5)
				(thermal_bridge_width 0.5)
				(island_removal_mode 0)
			)
			(polygon
				(pts
					(xy 13.97 -101.727) (xy 14.478 -101.727) (xy 14.478 -101.346) (xy 13.97 -101.346)
				)
			)
		)
		(zone
			(layer "F.Cu")
			(hatch none 0.5)
			(connect_pads
				(clearance 0)
			)
			(min_thickness 0.25)
			(keepout
				(tracks not_allowed)
				(vias allowed)
				(pads allowed)
				(copperpour not_allowed)
				(footprints allowed)
			)
			(placement
				(enabled no)
				(sheetname "")
			)
			(fill
				(thermal_gap 0.5)
				(thermal_bridge_width 0.5)
				(island_removal_mode 0)
			)
			(polygon
				(pts
					(xy 13.97 -101.346) (xy 14.478 -101.346) (xy 14.478 -101.727) (xy 13.97 -101.727)
				)
			)
		)
	)
	(footprint ""
		(layer "F.Cu")
		(at 356.98684 -134.22757)
		(property "Reference" "C7B2"
			(at 0 0 0)
			(layer "F.SilkS")
			(hide yes)
			(effects
				(font
					(size 1.27 1.27)
				)
			)
		)
		(property "Value" ""
			(at 0 0 0)
			(layer "F.Fab")
			(effects
				(font
					(size 1.27 1.27)
				)
			)
		)
		(duplicate_pad_numbers_are_jumpers no)
		(fp_rect
			(start -0.3048 0.9906)
			(end 0.3048 -0.1016)
			(stroke
				(width 0)
				(type default)
			)
			(fill no)
			(layer "F.CrtYd")
		)
		(fp_line
			(start -0.3048 -0.1016)
			(end -0.3048 0.9906)
			(stroke
				(width 0.1)
				(type default)
			)
			(layer "F.Fab")
		)
		(fp_line
			(start -0.3048 0.9906)
			(end 0.3048 0.9906)
			(stroke
				(width 0.1)
				(type default)
			)
			(layer "F.Fab")
		)
		(fp_line
			(start 0.3048 -0.1016)
			(end -0.3048 -0.1016)
			(stroke
				(width 0.1)
				(type default)
			)
			(layer "F.Fab")
		)
		(fp_line
			(start 0.3048 0.9906)
			(end 0.3048 -0.1016)
			(stroke
				(width 0.1)
				(type default)
			)
			(layer "F.Fab")
		)
		(pad "1" smd rect
			(at 0 0)
			(size 0.508 0.508)
			(layers "F.Cu" "F.Mask" "F.Paste")
			(net "VR_PVDDQ_DEF_VD12")
		)
		(pad "2" smd rect
			(at 0 0.889)
			(size 0.508 0.508)
			(layers "F.Cu" "F.Mask" "F.Paste")
			(net "GND")
		)
		(zone
			(layer "F.Cu")
			(hatch none 0.5)
			(connect_pads
				(clearance 0)
			)
			(min_thickness 0.25)
			(keepout
				(tracks allowed)
				(vias not_allowed)
				(pads allowed)
				(copperpour not_allowed)
				(footprints allowed)
			)
			(placement
				(enabled no)
				(sheetname "")
			)
			(fill
				(thermal_gap 0.5)
				(thermal_bridge_width 0.5)
				(island_removal_mode 0)
			)
			(polygon
				(pts
					(xy 356.73284 -133.59257) (xy 357.24084 -133.59257) (xy 357.24084 -133.97357) (xy 356.73284 -133.97357)
				)
			)
		)
		(zone
			(layer "F.Cu")
			(hatch none 0.5)
			(connect_pads
				(clearance 0)
			)
			(min_thickness 0.25)
			(keepout
				(tracks not_allowed)
				(vias allowed)
				(pads allowed)
				(copperpour not_allowed)
				(footprints allowed)
			)
			(placement
				(enabled no)
				(sheetname "")
			)
			(fill
				(thermal_gap 0.5)
				(thermal_bridge_width 0.5)
				(island_removal_mode 0)
			)
			(polygon
				(pts
					(xy 356.73284 -133.59257) (xy 357.24084 -133.59257) (xy 357.24084 -133.97357) (xy 356.73284 -133.97357)
				)
			)
		)
	)
	(footprint ""
		(layer "F.Cu")
		(at 353.216464 -144.502378 -90)
		(property "Reference" "RT31"
			(at 1.01473 0.656336 180)
			(unlocked yes)
			(layer "F.SilkS")
			(effects
				(font
					(size 0.4064 0.254)
					(thickness 0.1524)
				)
			)
		)
		(property "Value" ""
			(at 0 0 270)
			(layer "F.Fab")
			(effects
				(font
					(size 1.27 1.27)
				)
			)
		)
		(duplicate_pad_numbers_are_jumpers no)
		(fp_poly
			(pts
				(xy -0.4953 -0.2032) (xy 0.4953 -0.2032) (xy 0.4953 1.6002) (xy -0.4953 1.6002)
			)
			(stroke
				(width 0)
				(type default)
			)
			(fill no)
			(layer "F.CrtYd")
		)
		(fp_line
			(start -0.4953 1.6002)
			(end -0.4953 -0.2032)
			(stroke
				(width 0.1)
				(type default)
			)
			(layer "F.Fab")
		)
		(fp_line
			(start 0.4953 1.6002)
			(end -0.4953 1.6002)
			(stroke
				(width 0.1)
				(type default)
			)
			(layer "F.Fab")
		)
		(fp_line
			(start -0.4953 -0.2032)
			(end 0.4953 -0.2032)
			(stroke
				(width 0.1)
				(type default)
			)
			(layer "F.Fab")
		)
		(fp_line
			(start 0.4953 -0.2032)
			(end 0.4953 1.6002)
			(stroke
				(width 0.1)
				(type default)
			)
			(layer "F.Fab")
		)
		(pad "1" smd rect
			(at 0 0 270)
			(size 0.762 0.889)
			(layers "F.Cu" "F.Mask" "F.Paste")
			(net "VR_PVDDQ_DEF_PH2_BOOT")
		)
		(pad "2" smd rect
			(at 0 1.397 270)
			(size 0.762 0.889)
			(layers "F.Cu" "F.Mask" "F.Paste")
			(net "VR_PVDDQ_DEF_PH2_BOOT_R")
		)
		(zone
			(layer "F.Cu")
			(hatch none 0.5)
			(connect_pads
				(clearance 0)
			)
			(min_thickness 0.25)
			(keepout
				(tracks not_allowed)
				(vias allowed)
				(pads allowed)
				(copperpour not_allowed)
				(footprints allowed)
			)
			(placement
				(enabled no)
				(sheetname "")
			)
			(fill
				(thermal_gap 0.5)
				(thermal_bridge_width 0.5)
				(island_removal_mode 0)
			)
			(polygon
				(pts
					(xy 352.263964 -144.883378) (xy 352.263964 -144.121378) (xy 352.771964 -144.121378) (xy 352.771964 -144.883378)
				)
			)
		)
		(zone
			(layer "F.Cu")
			(hatch none 0.5)
			(connect_pads
				(clearance 0)
			)
			(min_thickness 0.25)
			(keepout
				(tracks allowed)
				(vias not_allowed)
				(pads allowed)
				(copperpour not_allowed)
				(footprints allowed)
			)
			(placement
				(enabled no)
				(sheetname "")
			)
			(fill
				(thermal_gap 0.5)
				(thermal_bridge_width 0.5)
				(island_removal_mode 0)
			)
			(polygon
				(pts
					(xy 352.263964 -144.121378) (xy 352.771964 -144.121378) (xy 352.771964 -144.883378) (xy 352.263964 -144.883378)
				)
			)
		)
	)
)
